#ISCELL
  logical_power design_note *
  *
#ISCELL
  mstr_misc dns *
  *
#ISCELL
  pure_quanta quanta_title_block_c *
  *
#CELL
  pure_quanta q_res *
  page226_i1
#CELL
  pure_quanta q_res *
  page226_i10
#CELL
  pure_quanta q_res *
  page226_i11
#CELL
  pure_quanta q_res *
  page226_i12
#CELL
  pure_quanta q_res *
  page226_i13
#CELL
  pure_quanta q_res *
  page226_i14
#ISCELL
  logical_power universal_power *
  page226_i15
#CELL
  pure_quanta q_cap *
  page226_i16
#ISCELL
  logical_power universal_gnd *
  page226_i17
#CELL
  pure_quanta gtl2014pw *
  page226_i18
#ISCELL
  logical_power universal_gnd *
  page226_i19
#ISCELL
  standard offpage *
  page226_i2
#CELL
  pure_quanta q_res *
  page226_i20
#ISCELL
  standard offpage *
  page226_i21
#ISCELL
  standard offpage *
  page226_i22
#ISCELL
  standard offpage *
  page226_i26
#CELL
  pure_quanta q_cap *
  page226_i27
#ISCELL
  logical_power universal_power *
  page226_i28
#ISCELL
  logical_power universal_gnd *
  page226_i29
#ISCELL
  standard offpage *
  page226_i3
#ISCELL
  logical_power universal_power *
  page226_i30
#CELL
  pure_quanta q_res *
  page226_i31
#ISCELL
  logical_power universal_gnd *
  page226_i32
#CELL
  pure_quanta q_res *
  page226_i34
#CELL
  pure_quanta q_res *
  page226_i36
#CELL
  pure_quanta q_res *
  page226_i37
#CELL
  pure_quanta nx3l2267gm *
  page226_i38
#ISCELL
  logical_power universal_gnd *
  page226_i39
#ISCELL
  standard offpage *
  page226_i4
#ISCELL
  standard offpage *
  page226_i40
#ISCELL
  standard offpage *
  page226_i41
#ISCELL
  logical_power universal_power *
  page226_i42
#CELL
  pure_quanta q_cap *
  page226_i43
#ISCELL
  logical_power universal_gnd *
  page226_i44
#CELL
  pure_quanta gtl2014pw *
  page226_i45
#ISCELL
  logical_power universal_gnd *
  page226_i46
#CELL
  pure_quanta q_res *
  page226_i47
#CELL
  pure_quanta q_res *
  page226_i48
#ISCELL
  logical_power universal_gnd *
  page226_i49
#ISCELL
  standard offpage *
  page226_i5
#ISCELL
  standard offpage *
  page226_i51
#ISCELL
  standard offpage *
  page226_i52
#ISCELL
  standard offpage *
  page226_i53
#ISCELL
  logical_power universal_power *
  page226_i54
#CELL
  pure_quanta q_cap *
  page226_i55
#ISCELL
  logical_power universal_gnd *
  page226_i56
#CELL
  pure_quanta q_res *
  page226_i57
#CELL
  pure_quanta q_res *
  page226_i58
#CELL
  pure_quanta q_res *
  page226_i59
#ISCELL
  logical_power universal_power *
  page226_i6
#ISCELL
  standard offpage *
  page226_i60
#ISCELL
  standard offpage *
  page226_i61
#ISCELL
  standard offpage *
  page226_i62
#ISCELL
  standard offpage *
  page226_i63
#CELL
  pure_quanta q_res *
  page226_i64
#CELL
  pure_quanta q_res *
  page226_i65
#ISCELL
  standard offpage *
  page226_i66
#ISCELL
  standard offpage *
  page226_i67
#CELL
  pure_quanta nx3l2267gm *
  page226_i68
#ISCELL
  logical_power universal_gnd *
  page226_i69
#CELL
  pure_quanta q_res *
  page226_i7
#ISCELL
  standard offpage *
  page226_i70
#ISCELL
  standard offpage *
  page226_i71
#ISCELL
  standard offpage *
  page226_i72
#ISCELL
  logical_power universal_power *
  page226_i76
#CELL
  pure_quanta q_res *
  page226_i77
#ISCELL
  logical_power universal_gnd *
  page226_i78
#CELL
  pure_quanta q_res *
  page226_i79
#ISCELL
  logical_power universal_gnd *
  page226_i8
#CELL
  pure_quanta q_res *
  page226_i80
#ISCELL
  standard offpage *
  page226_i81
#CELL
  pure_quanta q_res *
  page226_i82
#ISCELL
  standard offpage *
  page226_i83
#ISCELL
  standard offpage *
  page226_i84
#ISCELL
  standard offpage *
  page226_i85
#ISCELL
  logical_power universal_power *
  page226_i86
#CELL
  pure_quanta q_res *
  page226_i87
#CELL
  pure_quanta q_res *
  page226_i88
#CELL
  pure_quanta q_res *
  page226_i89
#ISCELL
  logical_power universal_power *
  page226_i9
#CELL
  pure_quanta q_res *
  page226_i90
#CELL
  pure_quanta q_res *
  page226_i91
#ISCELL
  logical_power universal_power *
  page226_i92
#CELL
  pure_quanta q_cap *
  page226_i93
#ISCELL
  standard offpage *
  page226_i94
#ISCELL
  standard offpage *
  page226_i95
